# S9S_MB_2U (Grand Teton) — schematic netlist excerpt (pin names and nets, part order shuffled) for the footprints in the layout excerpt that follows; sources: Cadence DE-HDL packaged netlist, KiCad conversion of 03242023_DA0F0TMBIJ0_F0T_Motherboard_J_brd_V01_OCP.brd

R3463  Q_RES  54.9K 1% CHIP  pkg 0402LF  page 147 : A = GPU_BASE_HMC_READY ; B = GND

U323  74LVC1G08W57  74LVC1G08W5-7 IC  pkg SOT25-5_0-95_3X1-6  page 164
  A  = HP_OCP_V3_2_RST_R
  B  = HP_LVC3_OCP_V3_2_P12V_PWRGD
  GND  = GND
  Y  = HP_LVC3_OCP_V3_2_PWRGD
  VCC  = P3V3_AUX

(kicad_pcb
	(version 20260206)
	(generator "pcbnew")
	(generator_version "10.0")
	(general
		(thickness 1.6)
		(legacy_teardrops no)
	)
	(paper "A4")
	(title_block
		(title "03242023_DA0F0TMBIJ0_F0T_Motherboard_J_brd_V01_OCP.brd")
		(comment 1 "Grand Teton / footprints 21-22 of 6105")
	)
	(layers
		(0 "F.Cu" signal "TOP")
		(4 "In1.Cu" signal "GND")
		(6 "In2.Cu" signal "IN1")
		(8 "In3.Cu" signal "GND1")
		(10 "In4.Cu" signal "IN2")
		(12 "In5.Cu" signal "GND2")
		(14 "In6.Cu" signal "IN3")
		(16 "In7.Cu" signal "GND3")
		(18 "In8.Cu" signal "VCC")
		(20 "In9.Cu" signal "VCC1")
		(22 "In10.Cu" signal "GND4")
		(24 "In11.Cu" signal "IN4")
		(26 "In12.Cu" signal "GND5")
		(28 "In13.Cu" signal "IN5")
		(30 "In14.Cu" signal "GND6")
		(32 "In15.Cu" signal "IN6")
		(34 "In16.Cu" signal "GND7")
		(2 "B.Cu" signal "BOTTOM")
		(9 "F.Adhes" user "F.Adhesive")
		(11 "B.Adhes" user "B.Adhesive")
		(13 "F.Paste" user "Package Geometry/Pastemask Top")
		(15 "B.Paste" user "Package Geometry/Pastemask Bottom")
		(5 "F.SilkS" user "Ref Des/Silkscreen Top")
		(7 "B.SilkS" user "Ref Des/Silkscreen Bottom")
		(1 "F.Mask" user "Board Geometry/Soldermask Top")
		(3 "B.Mask" user "Board Geometry/Soldermask Bottom")
		(17 "Dwgs.User" user "User.Drawings")
		(19 "Cmts.User" user "User.Comments")
		(21 "Eco1.User" user "User.Eco1")
		(23 "Eco2.User" user "User.Eco2")
		(25 "Edge.Cuts" user "Board Geometry/Outline")
		(27 "Margin" user)
		(31 "F.CrtYd" user "Package Geometry/Place Bound Top")
		(29 "B.CrtYd" user "Package Geometry/Place Bound Bottom")
		(35 "F.Fab" user "Ref Des/Assembly Top")
		(33 "B.Fab" user "Ref Des/Assembly Bottom")
	)
	(footprint ""
		(layer "F.Cu")
		(at 84.455 -38.699948 90)
		(property "Reference" "U323"
			(at 4.41833 -0.508 0)
			(unlocked yes)
			(layer "F.SilkS")
			(effects
				(font
					(size 0.7874 0.5842)
					(thickness 0.1524)
				)
				(justify left)
			)
		)
		(property "Value" ""
			(at 0 0 90)
			(layer "F.Fab")
			(effects
				(font
					(size 1.27 1.27)
				)
			)
		)
		(duplicate_pad_numbers_are_jumpers no)
		(fp_line
			(start 1.733296 -1.549908)
			(end 0.660908 -1.549908)
			(stroke
				(width 0.1524)
				(type default)
			)
			(layer "F.SilkS")
		)
		(fp_line
			(start 0.660908 -1.549908)
			(end 0 -0.889)
			(stroke
				(width 0.1524)
				(type default)
			)
			(layer "F.SilkS")
		)
		(fp_line
			(start -0.660908 -1.549908)
			(end -1.733296 -1.549908)
			(stroke
				(width 0.1524)
				(type default)
			)
			(layer "F.SilkS")
		)
		(fp_line
			(start -1.733296 -1.549908)
			(end -1.733296 1.549908)
			(stroke
				(width 0.1524)
				(type default)
			)
			(layer "F.SilkS")
		)
		(fp_line
			(start 0 -0.889)
			(end -0.660908 -1.549908)
			(stroke
				(width 0.1524)
				(type default)
			)
			(layer "F.SilkS")
		)
		(fp_line
			(start 1.733296 1.549908)
			(end 1.733296 -1.549908)
			(stroke
				(width 0.1524)
				(type default)
			)
			(layer "F.SilkS")
		)
		(fp_line
			(start -1.733296 1.549908)
			(end 1.733296 1.549908)
			(stroke
				(width 0.1524)
				(type default)
			)
			(layer "F.SilkS")
		)
		(fp_poly
			(pts
				(xy -2.299716 -2.047748) (xy -2.646934 -1.676654) (xy -2.102358 -1.51511)
			)
			(stroke
				(width 0)
				(type default)
			)
			(fill yes)
			(layer "F.SilkS")
		)
		(fp_line
			(start 0.849884 -1.549908)
			(end -0.849884 -1.549908)
			(stroke
				(width 0.1)
				(type default)
			)
			(layer "F.Fab")
		)
		(fp_line
			(start -0.849884 -1.549908)
			(end -0.849884 1.549908)
			(stroke
				(width 0.1)
				(type default)
			)
			(layer "F.Fab")
		)
		(fp_line
			(start 0.849884 1.549908)
			(end 0.849884 -1.549908)
			(stroke
				(width 0.1)
				(type default)
			)
			(layer "F.Fab")
		)
		(fp_line
			(start -0.849884 1.549908)
			(end 0.849884 1.549908)
			(stroke
				(width 0.1)
				(type default)
			)
			(layer "F.Fab")
		)
		(fp_poly
			(pts
				(xy -2.4384 -1.20396) (xy -2.4384 -0.69596) (xy -1.9304 -0.94996)
			)
			(stroke
				(width 0)
				(type default)
			)
			(fill yes)
			(layer "F.Fab")
		)
		(pad "1" smd rect
			(at -1.199896 -0.94996)
			(size 0.5588 0.8128)
			(layers "F.Cu" "F.Mask" "F.Paste")
			(net "HP_OCP_V3_2_RST_R")
		)
		(pad "2" smd rect
			(at -1.199896 0)
			(size 0.5588 0.8128)
			(layers "F.Cu" "F.Mask" "F.Paste")
			(net "HP_LVC3_OCP_V3_2_P12V_PWRGD")
		)
		(pad "3" smd rect
			(at -1.199896 0.94996)
			(size 0.5588 0.8128)
			(layers "F.Cu" "F.Mask" "F.Paste")
			(net "GND")
		)
		(pad "4" smd rect
			(at 1.199896 0.94996)
			(size 0.5588 0.8128)
			(layers "F.Cu" "F.Mask" "F.Paste")
			(net "HP_LVC3_OCP_V3_2_PWRGD")
		)
		(pad "5" smd rect
			(at 1.199896 -0.94996)
			(size 0.5588 0.8128)
			(layers "F.Cu" "F.Mask" "F.Paste")
			(net "P3V3_AUX")
		)
	)
	(footprint ""
		(layer "F.Cu")
		(at 169.441622 -421.527478 180)
		(property "Reference" "R3463"
			(at 0 0 180)
			(layer "F.SilkS")
			(hide yes)
			(effects
				(font
					(size 1.27 1.27)
				)
			)
		)
		(property "Value" ""
			(at 0 0 180)
			(layer "F.Fab")
			(effects
				(font
					(size 1.27 1.27)
				)
			)
		)
		(duplicate_pad_numbers_are_jumpers no)
		(fp_line
			(start 0.7874 0.4064)
			(end -0.7874 0.4064)
			(stroke
				(width 0.1524)
				(type default)
			)
			(layer "F.SilkS")
		)
		(fp_line
			(start 0.7874 -0.4064)
			(end 0.7874 0.4064)
			(stroke
				(width 0.1524)
				(type default)
			)
			(layer "F.SilkS")
		)
		(fp_line
			(start -0.7874 0.4064)
			(end -0.7874 -0.4064)
			(stroke
				(width 0.1524)
				(type default)
			)
			(layer "F.SilkS")
		)
		(fp_line
			(start -0.7874 -0.4064)
			(end 0.7874 -0.4064)
			(stroke
				(width 0.1524)
				(type default)
			)
			(layer "F.SilkS")
		)
		(fp_line
			(start 0.67945 0.3048)
			(end 0.120396 0.3048)
			(stroke
				(width 0.1)
				(type default)
			)
			(layer "F.Fab")
		)
		(fp_line
			(start 0.67945 -0.3048)
			(end 0.67945 0.3048)
			(stroke
				(width 0.1)
				(type default)
			)
			(layer "F.Fab")
		)
		(fp_line
			(start 0.12065 -0.2794)
			(end 0.12065 -0.3048)
			(stroke
				(width 0.1)
				(type default)
			)
			(layer "F.Fab")
		)
		(fp_line
			(start 0.12065 -0.3048)
			(end 0.67945 -0.3048)
			(stroke
				(width 0.1)
				(type default)
			)
			(layer "F.Fab")
		)
		(fp_line
			(start 0.120396 0.3048)
			(end 0.120396 0.2794)
			(stroke
				(width 0.1)
				(type default)
			)
			(layer "F.Fab")
		)
		(fp_line
			(start 0.120396 0.2794)
			(end -0.12065 0.2794)
			(stroke
				(width 0.1)
				(type default)
			)
			(layer "F.Fab")
		)
		(fp_line
			(start -0.12065 0.3048)
			(end -0.67945 0.3048)
			(stroke
				(width 0.1)
				(type default)
			)
			(layer "F.Fab")
		)
		(fp_line
			(start -0.12065 0.2794)
			(end -0.12065 0.3048)
			(stroke
				(width 0.1)
				(type default)
			)
			(layer "F.Fab")
		)
		(fp_line
			(start -0.12065 -0.2794)
			(end 0.12065 -0.2794)
			(stroke
				(width 0.1)
				(type default)
			)
			(layer "F.Fab")
		)
		(fp_line
			(start -0.12065 -0.305054)
			(end -0.12065 -0.2794)
			(stroke
				(width 0.1)
				(type default)
			)
			(layer "F.Fab")
		)
		(fp_line
			(start -0.67945 0.3048)
			(end -0.67945 -0.305054)
			(stroke
				(width 0.1)
				(type default)
			)
			(layer "F.Fab")
		)
		(fp_line
			(start -0.67945 -0.305054)
			(end -0.12065 -0.305054)
			(stroke
				(width 0.1)
				(type default)
			)
			(layer "F.Fab")
		)
		(pad "1" smd circle
			(at -0.40005 0 180)
			(size 0 0)
			(layers "F.Cu" "F.Mask" "F.Paste")
			(net "GPU_BASE_HMC_READY")
		)
		(pad "2" smd circle
			(at 0.40005 0 180)
			(size 0 0)
			(layers "F.Cu" "F.Mask" "F.Paste")
			(net "GND")
		)
	)
)
